# TIMECARD (Time Appliance Project (Time Card)) — schematic netlist excerpt (pin names and nets, part order shuffled) for the footprints in the layout excerpt that follows; sources: Cadence DE-HDL packaged netlist, KiCad conversion of R4006-B0001-02_R01.brd

R273  RESISTOR  100OHM 1%  pkg SMC_0402R_H016  page 26 : \1\ = FPGA_OUT_SMA2_LED_BLUE_N ; \2\ = UNNAMED_14_LED4PV14_I266_1
SP32  SOLDER_PREFORM  pkg 0201_SOLDER_PREFORM_4MIL  page 34 : \1\ = NC ; \2\ = NC
TP53  TP_PIONT  pkg TP010CT020B030_PTH  page 25 : \1\ = XP3R3V

(kicad_pcb
	(version 20260206)
	(generator "pcbnew")
	(generator_version "10.0")
	(general
		(thickness 1.6)
		(legacy_teardrops no)
	)
	(paper "A4")
	(title_block
		(title "timecard-production-celestica-r4006 — R4006-B0001-02_R01.brd")
		(comment 1 "Time Appliance Project (Time Card) / footprints 457-459 of 1113")
	)
	(layers
		(0 "F.Cu" signal "TOP")
		(4 "In1.Cu" signal "L02_GND1")
		(6 "In2.Cu" signal "L03_SIG1")
		(8 "In3.Cu" signal "L04_GND2")
		(10 "In4.Cu" signal "L05_VCC1")
		(12 "In5.Cu" signal "L06_VCC2")
		(14 "In6.Cu" signal "L07_GND3")
		(16 "In7.Cu" signal "L08_SIG2")
		(18 "In8.Cu" signal "L09_GND4")
		(2 "B.Cu" signal "BOTTOM")
		(9 "F.Adhes" user "F.Adhesive")
		(11 "B.Adhes" user "B.Adhesive")
		(13 "F.Paste" user "Package Geometry/Pastemask Top")
		(15 "B.Paste" user "Package Geometry/Pastemask Bottom")
		(5 "F.SilkS" user "Ref Des/Silkscreen Top")
		(7 "B.SilkS" user "Ref Des/Silkscreen Bottom")
		(1 "F.Mask" user "Board Geometry/Soldermask Top")
		(3 "B.Mask" user "Board Geometry/Soldermask Bottom")
		(17 "Dwgs.User" user "User.Drawings")
		(19 "Cmts.User" user "User.Comments")
		(21 "Eco1.User" user "User.Eco1")
		(23 "Eco2.User" user "User.Eco2")
		(25 "Edge.Cuts" user "Board Geometry/Outline")
		(27 "Margin" user)
		(31 "F.CrtYd" user "Package Geometry/Place Bound Top")
		(29 "B.CrtYd" user "Package Geometry/Place Bound Bottom")
		(35 "F.Fab" user "Ref Des/Assembly Top")
		(33 "B.Fab" user "Ref Des/Assembly Bottom")
	)
	(footprint ""
		(layer "F.Cu")
		(at 108.966 -69.596)
		(property "Reference" "TP53"
			(at -0.9652 1.43637 0)
			(unlocked yes)
			(layer "F.SilkS")
			(effects
				(font
					(size 0.7874 0.5842)
					(thickness 0.1524)
				)
				(justify left)
			)
		)
		(property "Value" ""
			(at 0 0 0)
			(layer "F.Fab")
			(effects
				(font
					(size 1.27 1.27)
				)
			)
		)
		(property "Device Type" "TP_PIONT-TP010CT020B030_PTH-TPA"
			(at -1.341882 0.996696 0)
			(unlocked yes)
			(layer "F.Fab")
			(hide yes)
			(effects
				(font
					(size 0.7874 0.5842)
					(thickness 0.1524)
				)
				(justify left)
			)
		)
		(duplicate_pad_numbers_are_jumpers no)
		(fp_poly
			(pts
				(arc
					(start 0.889 0)
					(mid -0.889 0)
					(end 0.889 0)
				)
			)
			(stroke
				(width 0)
				(type default)
			)
			(fill no)
			(layer "B.CrtYd")
		)
		(fp_poly
			(pts
				(arc
					(start 0.889 0)
					(mid -0.889 0)
					(end 0.889 0)
				)
			)
			(stroke
				(width 0)
				(type default)
			)
			(fill no)
			(layer "F.CrtYd")
		)
		(pad "1" thru_hole circle
			(at 0 0)
			(size 0.508 0.508)
			(drill 0.254)
			(layers "*.Cu" "*.Mask")
			(remove_unused_layers no)
			(net "XP3R3V")
			(clearance 0.1016)
			(padstack
				(mode front_inner_back)
				(layer "Inner"
					(shape circle)
					(size 0.508 0.508)
					(clearance 0.1016)
				)
				(layer "B.Cu"
					(shape circle)
					(size 0.762 0.762)
					(clearance -0.0254)
				)
			)
		)
	)
	(footprint ""
		(layer "F.Cu")
		(at 65.532 -136.017)
		(property "Reference" "SP32"
			(at 0 0 0)
			(layer "F.SilkS")
			(hide yes)
			(effects
				(font
					(size 1.27 1.27)
				)
			)
		)
		(property "Value" ""
			(at 0 0 0)
			(layer "F.Fab")
			(effects
				(font
					(size 1.27 1.27)
				)
			)
		)
		(duplicate_pad_numbers_are_jumpers no)
	)
	(footprint ""
		(layer "F.Cu")
		(at 20.32 -27.94 180)
		(property "Reference" "R273"
			(at -2.794 -0.54737 0)
			(unlocked yes)
			(layer "F.SilkS")
			(effects
				(font
					(size 0.7874 0.5842)
					(thickness 0.1524)
				)
			)
		)
		(property "Value" "VAL*"
			(at 0.02032 2.13233 180)
			(unlocked yes)
			(layer "F.Fab")
			(hide yes)
			(effects
				(font
					(size 0.7874 0.5842)
					(thickness 0.1524)
				)
			)
		)
		(property "Device Type" "RESISTOR-G155-11000-01,100OHM,A"
			(at 0.008382 1.210564 180)
			(unlocked yes)
			(layer "F.Fab")
			(hide yes)
			(effects
				(font
					(size 0.7874 0.5842)
					(thickness 0.1524)
				)
			)
		)
		(property "User Part Number" "PARTNUM*"
			(at 0.02032 4.024884 180)
			(unlocked yes)
			(layer "Cmts.User")
			(hide yes)
			(effects
				(font
					(size 0.7874 0.5842)
					(thickness 0.1524)
				)
			)
		)
		(property "Tolerance" "TOL*"
			(at 0.044704 3.05435 180)
			(unlocked yes)
			(layer "Cmts.User")
			(hide yes)
			(effects
				(font
					(size 0.7874 0.5842)
					(thickness 0.1524)
				)
			)
		)
		(duplicate_pad_numbers_are_jumpers no)
		(fp_line
			(start 1.143 0.5588)
			(end 1.143 -0.5588)
			(stroke
				(width 0.1)
				(type default)
			)
			(layer "F.SilkS")
		)
		(fp_line
			(start 1.143 -0.5588)
			(end -1.143 -0.5588)
			(stroke
				(width 0.1)
				(type default)
			)
			(layer "F.SilkS")
		)
		(fp_line
			(start -1.143 0.5588)
			(end 1.143 0.5588)
			(stroke
				(width 0.1)
				(type default)
			)
			(layer "F.SilkS")
		)
		(fp_line
			(start -1.143 -0.5588)
			(end -1.143 0.5588)
			(stroke
				(width 0.1)
				(type default)
			)
			(layer "F.SilkS")
		)
		(fp_poly
			(pts
				(xy -1.143 0.5588) (xy 1.143 0.5588) (xy 1.143 -0.5588) (xy -1.143 -0.5588)
			)
			(stroke
				(width 0)
				(type default)
			)
			(fill no)
			(layer "F.CrtYd")
		)
		(fp_line
			(start 0.508 0.3048)
			(end 0.508 -0.3048)
			(stroke
				(width 0.1)
				(type default)
			)
			(layer "F.Fab")
		)
		(fp_line
			(start 0.508 -0.3048)
			(end -0.508 -0.3048)
			(stroke
				(width 0.1)
				(type default)
			)
			(layer "F.Fab")
		)
		(fp_line
			(start -0.508 0.3048)
			(end 0.508 0.3048)
			(stroke
				(width 0.1)
				(type default)
			)
			(layer "F.Fab")
		)
		(fp_line
			(start -0.508 -0.3048)
			(end -0.508 0.3048)
			(stroke
				(width 0.1)
				(type default)
			)
			(layer "F.Fab")
		)
		(pad "1" smd rect
			(at -0.5334 0 180)
			(size 0.7112 0.6096)
			(layers "F.Cu" "F.Mask" "F.Paste")
			(net "FPGA_OUT_SMA2_LED_BLUE_N")
		)
		(pad "2" smd rect
			(at 0.5334 0 180)
			(size 0.7112 0.6096)
			(layers "F.Cu" "F.Mask" "F.Paste")
			(net "UNNAMED_14_LED4PV14_I266_1")
		)
		(zone
			(layer "F.Cu")
			(hatch none 0.5)
			(connect_pads
				(clearance 0)
			)
			(min_thickness 0.25)
			(keepout
				(tracks not_allowed)
				(vias allowed)
				(pads allowed)
				(copperpour not_allowed)
				(footprints allowed)
			)
			(placement
				(enabled no)
				(sheetname "")
			)
			(fill
				(thermal_gap 0.5)
				(thermal_bridge_width 0.5)
				(island_removal_mode 0)
			)
			(polygon
				(pts
					(xy 20.3962 -28.2448) (xy 20.2438 -28.2448) (xy 20.2438 -27.6352) (xy 20.3962 -27.6352)
				)
			)
		)
		(zone
			(layer "F.Cu")
			(hatch none 0.5)
			(connect_pads
				(clearance 0)
			)
			(min_thickness 0.25)
			(keepout
				(tracks allowed)
				(vias not_allowed)
				(pads allowed)
				(copperpour not_allowed)
				(footprints allowed)
			)
			(placement
				(enabled no)
				(sheetname "")
			)
			(fill
				(thermal_gap 0.5)
				(thermal_bridge_width 0.5)
				(island_removal_mode 0)
			)
			(polygon
				(pts
					(xy 20.3962 -28.2448) (xy 20.2438 -28.2448) (xy 20.2438 -27.6352) (xy 20.3962 -27.6352)
				)
			)
		)
	)
)
